(kicad_pcb
	(version 20241229)
	(generator "pcbnew")
	(generator_version "9.0")
	(general
		(thickness 1.711)
		(legacy_teardrops no)
	)
	(paper "A4")
	(title_block
		(title "Antmicro Baseboard for Jetson AGX Thor")
		(date "2026-02-18")
		(rev "1.1.0")
		(company "Antmicro Ltd")
		(comment 1 "www.antmicro.com")
		(comment 9 "footprints 435-439 of 1170")
	)
	(layers
		(0 "F.Cu" signal)
		(4 "In1.Cu" signal)
		(6 "In2.Cu" signal)
		(8 "In3.Cu" signal)
		(10 "In4.Cu" jumper)
		(12 "In5.Cu" signal)
		(14 "In6.Cu" signal)
		(16 "In7.Cu" signal)
		(18 "In8.Cu" signal)
		(2 "B.Cu" signal)
		(9 "F.Adhes" user "F.Adhesive")
		(11 "B.Adhes" user "B.Adhesive")
		(13 "F.Paste" user)
		(15 "B.Paste" user)
		(5 "F.SilkS" user "F.Silkscreen")
		(7 "B.SilkS" user "B.Silkscreen")
		(1 "F.Mask" user)
		(3 "B.Mask" user)
		(17 "Dwgs.User" user "User.Drawings")
		(19 "Cmts.User" user "User.Comments")
		(21 "Eco1.User" user "User.Eco1")
		(23 "Eco2.User" user "User.Eco2")
		(25 "Edge.Cuts" user)
		(27 "Margin" user)
		(31 "F.CrtYd" user "F.Courtyard")
		(29 "B.CrtYd" user "B.Courtyard")
		(35 "F.Fab" user)
		(33 "B.Fab" user)
	)
	(footprint "antmicro-footprints:R_0402_1005Metric"
		(layer "F.Cu")
		(at 63.839 58.171 90)
		(descr "Resistor SMD 0402")
		(tags "resistor SMD 0402")
		(property "Reference" "R163"
			(at -1.429 -1.539 90)
			(layer "F.SilkS")
			(effects
				(font
					(size 0.7 0.7)
					(thickness 0.15)
				)
				(justify left bottom)
			)
		)
		(property "Value" "R_0R_0402"
			(at -1.011843 1.772047 90)
			(layer "F.Fab")
			(effects
				(font
					(size 0.7 0.7)
					(thickness 0.15)
				)
				(justify left bottom)
			)
		)
		(property "Datasheet" "https://industrial.panasonic.com/cdbs/www-data/pdf/RDA0000/AOA0000C301.pdf"
			(at 0 0 90)
			(layer "F.Fab")
			(hide yes)
			(effects
				(font
					(size 1.27 1.27)
					(thickness 0.15)
				)
			)
		)
		(property "Description" "SMD Chip Resistor, Jumper, 0 ohm, 100 mW, 0402 [1005 Metric], Thick Film, General Purpose"
			(at 0 0 90)
			(layer "F.Fab")
			(hide yes)
			(effects
				(font
					(size 1.27 1.27)
					(thickness 0.15)
				)
			)
		)
		(property "Manufacturer" "Panasonic"
			(at 0 0 90)
			(unlocked yes)
			(layer "F.Fab")
			(hide yes)
			(effects
				(font
					(size 1 1)
					(thickness 0.15)
				)
			)
		)
		(property "MPN" "ERJ2GE0R00X"
			(at 0 0 90)
			(unlocked yes)
			(layer "F.Fab")
			(hide yes)
			(effects
				(font
					(size 1 1)
					(thickness 0.15)
				)
			)
		)
		(property "Val" "0R"
			(at 0 0 90)
			(unlocked yes)
			(layer "F.Fab")
			(hide yes)
			(effects
				(font
					(size 1 1)
					(thickness 0.15)
				)
			)
		)
		(property "License" "Apache-2.0"
			(at 0 0 90)
			(unlocked yes)
			(layer "F.Fab")
			(hide yes)
			(effects
				(font
					(size 1 1)
					(thickness 0.15)
				)
			)
		)
		(property "Author" "Antmicro"
			(at 0 0 90)
			(unlocked yes)
			(layer "F.Fab")
			(hide yes)
			(effects
				(font
					(size 1 1)
					(thickness 0.15)
				)
			)
		)
		(property "Tolerance" "~"
			(at 0 0 90)
			(unlocked yes)
			(layer "F.Fab")
			(hide yes)
			(effects
				(font
					(size 1 1)
					(thickness 0.15)
				)
			)
		)
		(property "Current" "1A"
			(at 0 0 90)
			(unlocked yes)
			(layer "F.Fab")
			(hide yes)
			(effects
				(font
					(size 1 1)
					(thickness 0.15)
				)
			)
		)
		(sheetname "/CSI/")
		(sheetfile "csi.kicad_sch")
		(attr smd)
		(fp_rect
			(start -0.925 -0.47)
			(end 0.925 0.47)
			(stroke
				(width 0.05)
				(type default)
			)
			(fill no)
			(layer "F.CrtYd")
		)
		(fp_rect
			(start -0.5 -0.25)
			(end 0.5 0.25)
			(stroke
				(width 0.15)
				(type solid)
			)
			(fill no)
			(layer "F.Fab")
		)
		(fp_text user "Author: Antmicro"
			(at -0.95 4.169 90)
			(layer "F.Fab")
			(effects
				(font
					(size 0.7 0.7)
					(thickness 0.15)
				)
				(justify left bottom)
			)
		)
		(fp_text user "${REFERENCE}"
			(at -0.95 3.168 90)
			(layer "F.Fab")
			(effects
				(font
					(size 0.7 0.7)
					(thickness 0.15)
				)
				(justify left bottom)
			)
		)
		(fp_text user "License: Apache-2.0"
			(at -0.95 5.169 90)
			(layer "F.Fab")
			(effects
				(font
					(size 0.7 0.7)
					(thickness 0.15)
				)
				(justify left bottom)
			)
		)
		(pad "1" smd roundrect
			(at -0.48 0 90)
			(size 0.59 0.64)
			(layers "F.Cu" "F.Mask" "F.Paste")
			(roundrect_rratio 0.25)
			(net 984 "/CSI/I2C_MUX_SCL")
			(pintype "passive")
		)
		(pad "2" smd roundrect
			(at 0.48 0 90)
			(size 0.59 0.64)
			(layers "F.Cu" "F.Mask" "F.Paste")
			(roundrect_rratio 0.25)
			(net 983 "/CSI/I2C_{CAM}.SCL")
			(pintype "passive")
		)
	)
	(footprint "antmicro-footprints:R_0402_1005Metric"
		(layer "F.Cu")
		(at 180.554468 86.725 -90)
		(descr "Resistor SMD 0402")
		(tags "resistor SMD 0402")
		(property "Reference" "R41"
			(at -2.96 0.32 90)
			(layer "F.SilkS")
			(effects
				(font
					(size 0.7 0.7)
					(thickness 0.15)
				)
				(justify right top)
			)
		)
		(property "Value" "R_200k_0402"
			(at -1.011843 1.772047 90)
			(layer "F.Fab")
			(effects
				(font
					(size 0.7 0.7)
					(thickness 0.15)
				)
				(justify right top)
			)
		)
		(property "Datasheet" "https://www.bourns.com/docs/product-datasheets/cr.pdf"
			(at 0 0 90)
			(layer "F.Fab")
			(hide yes)
			(effects
				(font
					(size 1.27 1.27)
					(thickness 0.15)
				)
			)
		)
		(property "Description" "SMD Chip Resistor, 200 kohm, ± 1%, 62.5 mW, 0402 [1005 Metric], Thick Film, General Purpose"
			(at 0 0 90)
			(layer "F.Fab")
			(hide yes)
			(effects
				(font
					(size 1.27 1.27)
					(thickness 0.15)
				)
			)
		)
		(property "MPN" "CR0402-FX-2003GLF"
			(at 0 0 270)
			(unlocked yes)
			(layer "F.Fab")
			(hide yes)
			(effects
				(font
					(size 1 1)
					(thickness 0.15)
				)
			)
		)
		(property "Manufacturer" "Bourns"
			(at 0 0 270)
			(unlocked yes)
			(layer "F.Fab")
			(hide yes)
			(effects
				(font
					(size 1 1)
					(thickness 0.15)
				)
			)
		)
		(property "License" "Apache-2.0"
			(at 0 0 270)
			(unlocked yes)
			(layer "F.Fab")
			(hide yes)
			(effects
				(font
					(size 1 1)
					(thickness 0.15)
				)
			)
		)
		(property "Author" "Antmicro"
			(at 0 0 270)
			(unlocked yes)
			(layer "F.Fab")
			(hide yes)
			(effects
				(font
					(size 1 1)
					(thickness 0.15)
				)
			)
		)
		(property "Val" "200k"
			(at 0 0 270)
			(unlocked yes)
			(layer "F.Fab")
			(hide yes)
			(effects
				(font
					(size 1 1)
					(thickness 0.15)
				)
			)
		)
		(property "Tolerance" "1%"
			(at 0 0 270)
			(unlocked yes)
			(layer "F.Fab")
			(hide yes)
			(effects
				(font
					(size 1 1)
					(thickness 0.15)
				)
			)
		)
		(component_classes
			(class "DCDC_SOM")
		)
		(sheetname "/DCDC/")
		(sheetfile "dcdc.kicad_sch")
		(attr smd)
		(fp_rect
			(start -0.925 -0.47)
			(end 0.925 0.47)
			(stroke
				(width 0.05)
				(type default)
			)
			(fill no)
			(layer "F.CrtYd")
		)
		(fp_rect
			(start -0.5 -0.25)
			(end 0.5 0.25)
			(stroke
				(width 0.15)
				(type solid)
			)
			(fill no)
			(layer "F.Fab")
		)
		(fp_text user "${REFERENCE}"
			(at -0.95 3.168 90)
			(layer "F.Fab")
			(effects
				(font
					(size 0.7 0.7)
					(thickness 0.15)
				)
				(justify right top)
			)
		)
		(fp_text user "Author: Antmicro"
			(at -0.95 4.169 90)
			(layer "F.Fab")
			(effects
				(font
					(size 0.7 0.7)
					(thickness 0.15)
				)
				(justify right top)
			)
		)
		(fp_text user "License: Apache-2.0"
			(at -0.95 5.169 90)
			(layer "F.Fab")
			(effects
				(font
					(size 0.7 0.7)
					(thickness 0.15)
				)
				(justify right top)
			)
		)
		(pad "1" smd roundrect
			(at -0.48 0 270)
			(size 0.59 0.64)
			(layers "F.Cu" "F.Mask" "F.Paste")
			(roundrect_rratio 0.25)
			(net 1 "GND")
			(pintype "passive")
		)
		(pad "2" smd roundrect
			(at 0.48 0 270)
			(size 0.59 0.64)
			(layers "F.Cu" "F.Mask" "F.Paste")
			(roundrect_rratio 0.25)
			(net 1214 "/DCDC/16V_MODE2")
			(pintype "passive")
		)
	)
	(footprint "antmicro-footprints:R_0402_1005Metric"
		(layer "F.Cu")
		(at 136 108.1 180)
		(descr "Resistor SMD 0402")
		(tags "resistor SMD 0402")
		(property "Reference" "R401"
			(at 1 0.3 0)
			(layer "F.SilkS")
			(effects
				(font
					(size 0.7 0.7)
					(thickness 0.15)
				)
				(justify right top)
			)
		)
		(property "Value" "R_0R_0402"
			(at -1.011843 1.772047 0)
			(layer "F.Fab")
			(effects
				(font
					(size 0.7 0.7)
					(thickness 0.15)
				)
				(justify right top)
			)
		)
		(property "Datasheet" "https://industrial.panasonic.com/cdbs/www-data/pdf/RDA0000/AOA0000C301.pdf"
			(at 0 0 0)
			(layer "F.Fab")
			(hide yes)
			(effects
				(font
					(size 1.27 1.27)
					(thickness 0.15)
				)
			)
		)
		(property "Description" "SMD Chip Resistor, Jumper, 0 ohm, 100 mW, 0402 [1005 Metric], Thick Film, General Purpose"
			(at 0 0 0)
			(layer "F.Fab")
			(hide yes)
			(effects
				(font
					(size 1.27 1.27)
					(thickness 0.15)
				)
			)
		)
		(property "MPN" "ERJ2GE0R00X"
			(at 0 0 180)
			(unlocked yes)
			(layer "F.Fab")
			(hide yes)
			(effects
				(font
					(size 1 1)
					(thickness 0.15)
				)
			)
		)
		(property "Manufacturer" "Panasonic"
			(at 0 0 180)
			(unlocked yes)
			(layer "F.Fab")
			(hide yes)
			(effects
				(font
					(size 1 1)
					(thickness 0.15)
				)
			)
		)
		(property "License" "Apache-2.0"
			(at 0 0 180)
			(unlocked yes)
			(layer "F.Fab")
			(hide yes)
			(effects
				(font
					(size 1 1)
					(thickness 0.15)
				)
			)
		)
		(property "Author" "Antmicro"
			(at 0 0 180)
			(unlocked yes)
			(layer "F.Fab")
			(hide yes)
			(effects
				(font
					(size 1 1)
					(thickness 0.15)
				)
			)
		)
		(property "Val" "0R"
			(at 0 0 180)
			(unlocked yes)
			(layer "F.Fab")
			(hide yes)
			(effects
				(font
					(size 1 1)
					(thickness 0.15)
				)
			)
		)
		(property "Tolerance" "~"
			(at 0 0 180)
			(unlocked yes)
			(layer "F.Fab")
			(hide yes)
			(effects
				(font
					(size 1 1)
					(thickness 0.15)
				)
			)
		)
		(property "Current" "1A"
			(at 0 0 180)
			(unlocked yes)
			(layer "F.Fab")
			(hide yes)
			(effects
				(font
					(size 1 1)
					(thickness 0.15)
				)
			)
		)
		(sheetname "/Peripherals/")
		(sheetfile "peripherals.kicad_sch")
		(attr smd)
		(fp_rect
			(start -0.925 -0.47)
			(end 0.925 0.47)
			(stroke
				(width 0.05)
				(type default)
			)
			(fill no)
			(layer "F.CrtYd")
		)
		(fp_rect
			(start -0.5 -0.25)
			(end 0.5 0.25)
			(stroke
				(width 0.15)
				(type solid)
			)
			(fill no)
			(layer "F.Fab")
		)
		(fp_text user "${REFERENCE}"
			(at -0.95 3.168 0)
			(layer "F.Fab")
			(effects
				(font
					(size 0.7 0.7)
					(thickness 0.15)
				)
				(justify right top)
			)
		)
		(fp_text user "License: Apache-2.0"
			(at -0.95 5.169 0)
			(layer "F.Fab")
			(effects
				(font
					(size 0.7 0.7)
					(thickness 0.15)
				)
				(justify right top)
			)
		)
		(fp_text user "Author: Antmicro"
			(at -0.95 4.169 0)
			(layer "F.Fab")
			(effects
				(font
					(size 0.7 0.7)
					(thickness 0.15)
				)
				(justify right top)
			)
		)
		(pad "1" smd roundrect
			(at -0.48 0 180)
			(size 0.59 0.64)
			(layers "F.Cu" "F.Mask" "F.Paste")
			(roundrect_rratio 0.25)
			(net 1315 "/Peripherals/GPIOEX_P0_0")
			(pintype "passive")
		)
		(pad "2" smd roundrect
			(at 0.48 0 180)
			(size 0.59 0.64)
			(layers "F.Cu" "F.Mask" "F.Paste")
			(roundrect_rratio 0.25)
			(net 74 "/CSI/CAM_CTRL.CSIA_PEN")
			(pintype "passive")
		)
	)
	(footprint "antmicro-footprints:SOD-523"
		(layer "F.Cu")
		(at 135.7 65.2 180)
		(property "Reference" "D11"
			(at -3.14 0.4 0)
			(layer "F.SilkS")
			(effects
				(font
					(size 0.7 0.7)
					(thickness 0.15)
				)
				(justify right top)
			)
		)
		(property "Value" "PESD5Z5.0F"
			(at 0 1.499 0)
			(layer "F.Fab")
			(effects
				(font
					(size 0.7 0.7)
					(thickness 0.15)
				)
				(justify right top)
			)
		)
		(property "Datasheet" "https://assets.nexperia.com/documents/data-sheet/PESD5Z5_0.pdf"
			(at 0 0 0)
			(layer "F.Fab")
			(hide yes)
			(effects
				(font
					(size 1.27 1.27)
					(thickness 0.15)
				)
			)
		)
		(property "Description" "Unidirectional TVS, 30 kV,  SOD-523, 5 V, 89 pF"
			(at 0 0 0)
			(layer "F.Fab")
			(hide yes)
			(effects
				(font
					(size 1.27 1.27)
					(thickness 0.15)
				)
			)
		)
		(property "Manufacturer" "Nexperia"
			(at 0 0 180)
			(unlocked yes)
			(layer "F.Fab")
			(hide yes)
			(effects
				(font
					(size 1 1)
					(thickness 0.15)
				)
			)
		)
		(property "MPN" "PESD5Z5.0F"
			(at 0 0 180)
			(unlocked yes)
			(layer "F.Fab")
			(hide yes)
			(effects
				(font
					(size 1 1)
					(thickness 0.15)
				)
			)
		)
		(property "Author" "Antmicro"
			(at 0 0 180)
			(unlocked yes)
			(layer "F.Fab")
			(hide yes)
			(effects
				(font
					(size 1 1)
					(thickness 0.15)
				)
			)
		)
		(property "License" "Apache-2.0"
			(at 0 0 180)
			(unlocked yes)
			(layer "F.Fab")
			(hide yes)
			(effects
				(font
					(size 1 1)
					(thickness 0.15)
				)
			)
		)
		(sheetname "/Power/")
		(sheetfile "power.kicad_sch")
		(attr smd)
		(fp_line
			(start -0.35 -0.5)
			(end -0.35 0.5)
			(stroke
				(width 0.15)
				(type solid)
			)
			(layer "F.SilkS")
		)
		(fp_poly
			(pts
				(xy -1 -0.6) (xy -1 0.6) (xy 1 0.6) (xy 1 -0.6)
			)
			(stroke
				(width 0.05)
				(type solid)
			)
			(fill no)
			(layer "F.CrtYd")
		)
		(fp_line
			(start 0.65 -0.425)
			(end 0.65 0.423)
			(stroke
				(width 0.15)
				(type solid)
			)
			(layer "F.Fab")
		)
		(fp_line
			(start -0.35 -0.4)
			(end -0.35 0.4)
			(stroke
				(width 0.15)
				(type solid)
			)
			(layer "F.Fab")
		)
		(fp_line
			(start -0.652 0.423)
			(end 0.65 0.423)
			(stroke
				(width 0.15)
				(type solid)
			)
			(layer "F.Fab")
		)
		(fp_line
			(start -0.652 0.423)
			(end -0.652 -0.425)
			(stroke
				(width 0.15)
				(type solid)
			)
			(layer "F.Fab")
		)
		(fp_line
			(start -0.652 -0.425)
			(end 0.65 -0.425)
			(stroke
				(width 0.15)
				(type solid)
			)
			(layer "F.Fab")
		)
		(fp_text user "License: Apache-2.0"
			(at -1.276 5.9 0)
			(layer "F.Fab")
			(effects
				(font
					(size 0.7 0.7)
					(thickness 0.15)
				)
				(justify right top)
			)
		)
		(fp_text user "Author: Antmicro"
			(at -1.276 4.7 0)
			(layer "F.Fab")
			(effects
				(font
					(size 0.7 0.7)
					(thickness 0.15)
				)
				(justify right top)
			)
		)
		(fp_text user "${REFERENCE}"
			(at -1.276 3.499 0)
			(layer "F.Fab")
			(effects
				(font
					(size 0.7 0.7)
					(thickness 0.15)
				)
				(justify right top)
			)
		)
		(pad "1" smd roundrect
			(at -0.701 0 180)
			(size 0.5 0.6)
			(layers "F.Cu" "F.Mask" "F.Paste")
			(roundrect_rratio 0.25)
			(net 4 "+3V3_AON")
			(pinfunction "C")
			(pintype "passive")
		)
		(pad "2" smd roundrect
			(at 0.699001 0 180)
			(size 0.5 0.6)
			(layers "F.Cu" "F.Mask" "F.Paste")
			(roundrect_rratio 0.25)
			(net 1 "GND")
			(pinfunction "A")
			(pintype "passive")
		)
	)
	(footprint "antmicro-footprints:R_0402_1005Metric"
		(layer "F.Cu")
		(at 136 111.1 180)
		(descr "Resistor SMD 0402")
		(tags "resistor SMD 0402")
		(property "Reference" "R402"
			(at 1 0.3 0)
			(layer "F.SilkS")
			(effects
				(font
					(size 0.7 0.7)
					(thickness 0.15)
				)
				(justify right top)
			)
		)
		(property "Value" "R_0R_0402"
			(at -1.011843 1.772047 0)
			(layer "F.Fab")
			(effects
				(font
					(size 0.7 0.7)
					(thickness 0.15)
				)
				(justify right top)
			)
		)
		(property "Datasheet" "https://industrial.panasonic.com/cdbs/www-data/pdf/RDA0000/AOA0000C301.pdf"
			(at 0 0 0)
			(layer "F.Fab")
			(hide yes)
			(effects
				(font
					(size 1.27 1.27)
					(thickness 0.15)
				)
			)
		)
		(property "Description" "SMD Chip Resistor, Jumper, 0 ohm, 100 mW, 0402 [1005 Metric], Thick Film, General Purpose"
			(at 0 0 0)
			(layer "F.Fab")
			(hide yes)
			(effects
				(font
					(size 1.27 1.27)
					(thickness 0.15)
				)
			)
		)
		(property "MPN" "ERJ2GE0R00X"
			(at 0 0 180)
			(unlocked yes)
			(layer "F.Fab")
			(hide yes)
			(effects
				(font
					(size 1 1)
					(thickness 0.15)
				)
			)
		)
		(property "Manufacturer" "Panasonic"
			(at 0 0 180)
			(unlocked yes)
			(layer "F.Fab")
			(hide yes)
			(effects
				(font
					(size 1 1)
					(thickness 0.15)
				)
			)
		)
		(property "License" "Apache-2.0"
			(at 0 0 180)
			(unlocked yes)
			(layer "F.Fab")
			(hide yes)
			(effects
				(font
					(size 1 1)
					(thickness 0.15)
				)
			)
		)
		(property "Author" "Antmicro"
			(at 0 0 180)
			(unlocked yes)
			(layer "F.Fab")
			(hide yes)
			(effects
				(font
					(size 1 1)
					(thickness 0.15)
				)
			)
		)
		(property "Val" "0R"
			(at 0 0 180)
			(unlocked yes)
			(layer "F.Fab")
			(hide yes)
			(effects
				(font
					(size 1 1)
					(thickness 0.15)
				)
			)
		)
		(property "Tolerance" "~"
			(at 0 0 180)
			(unlocked yes)
			(layer "F.Fab")
			(hide yes)
			(effects
				(font
					(size 1 1)
					(thickness 0.15)
				)
			)
		)
		(property "Current" "1A"
			(at 0 0 180)
			(unlocked yes)
			(layer "F.Fab")
			(hide yes)
			(effects
				(font
					(size 1 1)
					(thickness 0.15)
				)
			)
		)
		(sheetname "/Peripherals/")
		(sheetfile "peripherals.kicad_sch")
		(attr smd)
		(fp_rect
			(start -0.925 -0.47)
			(end 0.925 0.47)
			(stroke
				(width 0.05)
				(type default)
			)
			(fill no)
			(layer "F.CrtYd")
		)
		(fp_rect
			(start -0.5 -0.25)
			(end 0.5 0.25)
			(stroke
				(width 0.15)
				(type solid)
			)
			(fill no)
			(layer "F.Fab")
		)
		(fp_text user "License: Apache-2.0"
			(at -0.95 5.169 0)
			(layer "F.Fab")
			(effects
				(font
					(size 0.7 0.7)
					(thickness 0.15)
				)
				(justify right top)
			)
		)
		(fp_text user "${REFERENCE}"
			(at -0.95 3.168 0)
			(layer "F.Fab")
			(effects
				(font
					(size 0.7 0.7)
					(thickness 0.15)
				)
				(justify right top)
			)
		)
		(fp_text user "Author: Antmicro"
			(at -0.95 4.169 0)
			(layer "F.Fab")
			(effects
				(font
					(size 0.7 0.7)
					(thickness 0.15)
				)
				(justify right top)
			)
		)
		(pad "1" smd roundrect
			(at -0.48 0 180)
			(size 0.59 0.64)
			(layers "F.Cu" "F.Mask" "F.Paste")
			(roundrect_rratio 0.25)
			(net 1312 "/Peripherals/GPIOEX_P0_3")
			(pintype "passive")
		)
		(pad "2" smd roundrect
			(at 0.48 0 180)
			(size 0.59 0.64)
			(layers "F.Cu" "F.Mask" "F.Paste")
			(roundrect_rratio 0.25)
			(net 117 "/CSI/CAM_CTRL.CSIB_FLG")
			(pintype "passive")
		)
	)
)
